# T6G (Grand Teton) — schematic netlist excerpt (pin names and nets, part order shuffled) for the footprints in the layout excerpt that follows; sources: Cadence DE-HDL packaged netlist, KiCad conversion of 04192023_DAF0TMB3IC0_F0TG_MB_C_brd_V02_OCP.brd

R6054  Q_RES  0 5% CHIP  pkg 0402LF  page 82 : A = FM_OCP_SFF_PWR_GOOD ; B = PWRGD_OCP_SFF_PWR_GOOD
C829  Q_CAP_DIFFBUS  DIFF BUS_0.22UF 6.3V 20% X6S  pkg C0201  page 65 : \1\ = P5E_CPU1_P0_TX_C_DP<4> ; \2\ = P5E_CPU1_P0_TX_DP<4>
R1362  Q_RES  33 5% CHIP  pkg 0402LF  page 188 : A = PWRGD_P3V3_R1 ; B = PWRGD_P3V3_R2

(kicad_pcb
	(version 20260206)
	(generator "pcbnew")
	(generator_version "10.0")
	(general
		(thickness 1.6)
		(legacy_teardrops no)
	)
	(paper "A4")
	(title_block
		(title "04192023_DAF0TMB3IC0_F0TG_MB_C_brd_V02_OCP.brd")
		(comment 1 "Grand Teton / footprints 3147-3149 of 8354")
	)
	(layers
		(0 "F.Cu" signal "TOP")
		(4 "In1.Cu" signal "GND")
		(6 "In2.Cu" signal "IN1")
		(8 "In3.Cu" signal "GND1")
		(10 "In4.Cu" signal "IN2")
		(12 "In5.Cu" signal "GND2")
		(14 "In6.Cu" signal "IN3")
		(16 "In7.Cu" signal "GND3")
		(18 "In8.Cu" signal "VCC")
		(20 "In9.Cu" signal "VCC1")
		(22 "In10.Cu" signal "GND4")
		(24 "In11.Cu" signal "IN4")
		(26 "In12.Cu" signal "GND5")
		(28 "In13.Cu" signal "IN5")
		(30 "In14.Cu" signal "GND6")
		(32 "In15.Cu" signal "IN6")
		(34 "In16.Cu" signal "GND7")
		(2 "B.Cu" signal "BOTTOM")
		(9 "F.Adhes" user "F.Adhesive")
		(11 "B.Adhes" user "B.Adhesive")
		(13 "F.Paste" user "Package Geometry/Pastemask Top")
		(15 "B.Paste" user "Package Geometry/Pastemask Bottom")
		(5 "F.SilkS" user "Ref Des/Silkscreen Top")
		(7 "B.SilkS" user "Ref Des/Silkscreen Bottom")
		(1 "F.Mask" user "Board Geometry/Soldermask Top")
		(3 "B.Mask" user "Board Geometry/Soldermask Bottom")
		(17 "Dwgs.User" user "User.Drawings")
		(19 "Cmts.User" user "User.Comments")
		(21 "Eco1.User" user "User.Eco1")
		(23 "Eco2.User" user "User.Eco2")
		(25 "Edge.Cuts" user "Board Geometry/Outline")
		(27 "Margin" user)
		(31 "F.CrtYd" user "Package Geometry/Place Bound Top")
		(29 "B.CrtYd" user "Package Geometry/Place Bound Bottom")
		(35 "F.Fab" user "Ref Des/Assembly Top")
		(33 "B.Fab" user "Ref Des/Assembly Bottom")
	)
	(footprint ""
		(layer "F.Cu")
		(at 186.387994 -133.537198 -90)
		(property "Reference" "R1362"
			(at 0 0 270)
			(layer "F.SilkS")
			(hide yes)
			(effects
				(font
					(size 1.27 1.27)
				)
			)
		)
		(property "Value" ""
			(at 0 0 270)
			(layer "F.Fab")
			(effects
				(font
					(size 1.27 1.27)
				)
			)
		)
		(duplicate_pad_numbers_are_jumpers no)
		(fp_line
			(start -0.7874 0.4064)
			(end -0.7874 -0.4064)
			(stroke
				(width 0.1524)
				(type default)
			)
			(layer "F.SilkS")
		)
		(fp_line
			(start 0.7874 0.4064)
			(end -0.7874 0.4064)
			(stroke
				(width 0.1524)
				(type default)
			)
			(layer "F.SilkS")
		)
		(fp_line
			(start -0.7874 -0.4064)
			(end 0.7874 -0.4064)
			(stroke
				(width 0.1524)
				(type default)
			)
			(layer "F.SilkS")
		)
		(fp_line
			(start 0.7874 -0.4064)
			(end 0.7874 0.4064)
			(stroke
				(width 0.1524)
				(type default)
			)
			(layer "F.SilkS")
		)
		(fp_line
			(start -0.67945 0.3048)
			(end -0.67945 -0.305054)
			(stroke
				(width 0.1)
				(type default)
			)
			(layer "F.Fab")
		)
		(fp_line
			(start -0.12065 0.3048)
			(end -0.67945 0.3048)
			(stroke
				(width 0.1)
				(type default)
			)
			(layer "F.Fab")
		)
		(fp_line
			(start 0.120396 0.3048)
			(end 0.120396 0.2794)
			(stroke
				(width 0.1)
				(type default)
			)
			(layer "F.Fab")
		)
		(fp_line
			(start 0.67945 0.3048)
			(end 0.120396 0.3048)
			(stroke
				(width 0.1)
				(type default)
			)
			(layer "F.Fab")
		)
		(fp_line
			(start -0.12065 0.2794)
			(end -0.12065 0.3048)
			(stroke
				(width 0.1)
				(type default)
			)
			(layer "F.Fab")
		)
		(fp_line
			(start 0.120396 0.2794)
			(end -0.12065 0.2794)
			(stroke
				(width 0.1)
				(type default)
			)
			(layer "F.Fab")
		)
		(fp_line
			(start -0.12065 -0.2794)
			(end 0.12065 -0.2794)
			(stroke
				(width 0.1)
				(type default)
			)
			(layer "F.Fab")
		)
		(fp_line
			(start 0.12065 -0.2794)
			(end 0.12065 -0.3048)
			(stroke
				(width 0.1)
				(type default)
			)
			(layer "F.Fab")
		)
		(fp_line
			(start 0.12065 -0.3048)
			(end 0.67945 -0.3048)
			(stroke
				(width 0.1)
				(type default)
			)
			(layer "F.Fab")
		)
		(fp_line
			(start 0.67945 -0.3048)
			(end 0.67945 0.3048)
			(stroke
				(width 0.1)
				(type default)
			)
			(layer "F.Fab")
		)
		(fp_line
			(start -0.67945 -0.305054)
			(end -0.12065 -0.305054)
			(stroke
				(width 0.1)
				(type default)
			)
			(layer "F.Fab")
		)
		(fp_line
			(start -0.12065 -0.305054)
			(end -0.12065 -0.2794)
			(stroke
				(width 0.1)
				(type default)
			)
			(layer "F.Fab")
		)
		(pad "1" smd circle
			(at -0.40005 0 270)
			(size 0 0)
			(layers "F.Cu" "F.Mask" "F.Paste")
			(net "PWRGD_P3V3_R1")
		)
		(pad "2" smd circle
			(at 0.40005 0 270)
			(size 0 0)
			(layers "F.Cu" "F.Mask" "F.Paste")
			(net "PWRGD_P3V3_R2")
		)
	)
	(footprint ""
		(layer "F.Cu")
		(at 48.095154 -375.49963 -90)
		(property "Reference" "C829"
			(at 0 0 270)
			(layer "F.SilkS")
			(hide yes)
			(effects
				(font
					(size 1.27 1.27)
				)
			)
		)
		(property "Value" ""
			(at 0 0 270)
			(layer "F.Fab")
			(effects
				(font
					(size 1.27 1.27)
				)
			)
		)
		(duplicate_pad_numbers_are_jumpers no)
		(fp_line
			(start -0.299974 0.150114)
			(end -0.299974 -0.150114)
			(stroke
				(width 0.1)
				(type default)
			)
			(layer "F.Fab")
		)
		(fp_line
			(start 0.299974 0.150114)
			(end -0.299974 0.150114)
			(stroke
				(width 0.1)
				(type default)
			)
			(layer "F.Fab")
		)
		(fp_line
			(start -0.299974 -0.150114)
			(end 0.299974 -0.150114)
			(stroke
				(width 0.1)
				(type default)
			)
			(layer "F.Fab")
		)
		(fp_line
			(start 0.299974 -0.150114)
			(end 0.299974 0.150114)
			(stroke
				(width 0.1)
				(type default)
			)
			(layer "F.Fab")
		)
		(pad "1" smd rect
			(at -0.2667 0 270)
			(size 0.3048 0.381)
			(layers "F.Cu" "F.Mask" "F.Paste")
			(net "P5E_CPU1_P0_TX_C_DP<4>")
		)
		(pad "2" smd rect
			(at 0.2667 0 270)
			(size 0.3048 0.381)
			(layers "F.Cu" "F.Mask" "F.Paste")
			(net "P5E_CPU1_P0_TX_DP<4>")
		)
	)
	(footprint ""
		(layer "F.Cu")
		(at 184.801256 -96.103948 90)
		(property "Reference" "R6054"
			(at 0 0 90)
			(layer "F.SilkS")
			(hide yes)
			(effects
				(font
					(size 1.27 1.27)
				)
			)
		)
		(property "Value" ""
			(at 0 0 90)
			(layer "F.Fab")
			(effects
				(font
					(size 1.27 1.27)
				)
			)
		)
		(duplicate_pad_numbers_are_jumpers no)
		(fp_line
			(start 0.7874 -0.4064)
			(end 0.7874 0.4064)
			(stroke
				(width 0.1524)
				(type default)
			)
			(layer "F.SilkS")
		)
		(fp_line
			(start -0.7874 -0.4064)
			(end 0.7874 -0.4064)
			(stroke
				(width 0.1524)
				(type default)
			)
			(layer "F.SilkS")
		)
		(fp_line
			(start 0.7874 0.4064)
			(end -0.7874 0.4064)
			(stroke
				(width 0.1524)
				(type default)
			)
			(layer "F.SilkS")
		)
		(fp_line
			(start -0.7874 0.4064)
			(end -0.7874 -0.4064)
			(stroke
				(width 0.1524)
				(type default)
			)
			(layer "F.SilkS")
		)
		(fp_line
			(start -0.12065 -0.305054)
			(end -0.12065 -0.2794)
			(stroke
				(width 0.1)
				(type default)
			)
			(layer "F.Fab")
		)
		(fp_line
			(start -0.67945 -0.305054)
			(end -0.12065 -0.305054)
			(stroke
				(width 0.1)
				(type default)
			)
			(layer "F.Fab")
		)
		(fp_line
			(start 0.67945 -0.3048)
			(end 0.67945 0.3048)
			(stroke
				(width 0.1)
				(type default)
			)
			(layer "F.Fab")
		)
		(fp_line
			(start 0.12065 -0.3048)
			(end 0.67945 -0.3048)
			(stroke
				(width 0.1)
				(type default)
			)
			(layer "F.Fab")
		)
		(fp_line
			(start 0.12065 -0.2794)
			(end 0.12065 -0.3048)
			(stroke
				(width 0.1)
				(type default)
			)
			(layer "F.Fab")
		)
		(fp_line
			(start -0.12065 -0.2794)
			(end 0.12065 -0.2794)
			(stroke
				(width 0.1)
				(type default)
			)
			(layer "F.Fab")
		)
		(fp_line
			(start 0.120396 0.2794)
			(end -0.12065 0.2794)
			(stroke
				(width 0.1)
				(type default)
			)
			(layer "F.Fab")
		)
		(fp_line
			(start -0.12065 0.2794)
			(end -0.12065 0.3048)
			(stroke
				(width 0.1)
				(type default)
			)
			(layer "F.Fab")
		)
		(fp_line
			(start 0.67945 0.3048)
			(end 0.120396 0.3048)
			(stroke
				(width 0.1)
				(type default)
			)
			(layer "F.Fab")
		)
		(fp_line
			(start 0.120396 0.3048)
			(end 0.120396 0.2794)
			(stroke
				(width 0.1)
				(type default)
			)
			(layer "F.Fab")
		)
		(fp_line
			(start -0.12065 0.3048)
			(end -0.67945 0.3048)
			(stroke
				(width 0.1)
				(type default)
			)
			(layer "F.Fab")
		)
		(fp_line
			(start -0.67945 0.3048)
			(end -0.67945 -0.305054)
			(stroke
				(width 0.1)
				(type default)
			)
			(layer "F.Fab")
		)
		(pad "1" smd circle
			(at -0.40005 0 90)
			(size 0 0)
			(layers "F.Cu" "F.Mask" "F.Paste")
			(net "FM_OCP_SFF_PWR_GOOD")
		)
		(pad "2" smd circle
			(at 0.40005 0 90)
			(size 0 0)
			(layers "F.Cu" "F.Mask" "F.Paste")
			(net "PWRGD_OCP_SFF_PWR_GOOD")
		)
	)
)
